(kicad_pcb
	(version 20260206)
	(generator "pcbnew")
	(generator_version "10.0")
	(general
		(thickness 1.6)
		(legacy_teardrops no)
	)
	(paper "A4")
	(title_block
		(title "12092022_DA0F0TMDCD0_F0T_Management_Board_D_brd_V3_OCP.brd")
		(comment 1 "Grand Teton / footprints 885-890 of 1440")
	)
	(layers
		(0 "F.Cu" signal "TOP")
		(4 "In1.Cu" signal "GND")
		(6 "In2.Cu" signal "IN1")
		(8 "In3.Cu" signal "GND1")
		(10 "In4.Cu" signal "IN2")
		(12 "In5.Cu" signal "VCC")
		(14 "In6.Cu" signal "VCC1")
		(16 "In7.Cu" signal "IN3")
		(18 "In8.Cu" signal "GND2")
		(20 "In9.Cu" signal "IN4")
		(22 "In10.Cu" signal "GND3")
		(2 "B.Cu" signal "BOTTOM")
		(9 "F.Adhes" user "F.Adhesive")
		(11 "B.Adhes" user "B.Adhesive")
		(13 "F.Paste" user "Package Geometry/Pastemask Top")
		(15 "B.Paste" user "Package Geometry/Pastemask Bottom")
		(5 "F.SilkS" user "Ref Des/Silkscreen Top")
		(7 "B.SilkS" user "Ref Des/Silkscreen Bottom")
		(1 "F.Mask" user "Board Geometry/Soldermask Top")
		(3 "B.Mask" user "Board Geometry/Soldermask Bottom")
		(17 "Dwgs.User" user "User.Drawings")
		(19 "Cmts.User" user "User.Comments")
		(21 "Eco1.User" user "User.Eco1")
		(23 "Eco2.User" user "User.Eco2")
		(25 "Edge.Cuts" user "Board Geometry/Outline")
		(27 "Margin" user)
		(31 "F.CrtYd" user "Package Geometry/Place Bound Top")
		(29 "B.CrtYd" user "Package Geometry/Place Bound Bottom")
		(35 "F.Fab" user "Ref Des/Assembly Top")
		(33 "B.Fab" user "Ref Des/Assembly Bottom")
	)
	(footprint ""
		(layer "B.Cu")
		(at 71.599806 -69.576188 -90)
		(property "Reference" "R687"
			(at 0 0 90)
			(layer "B.SilkS")
			(hide yes)
			(effects
				(font
					(size 1.27 1.27)
				)
				(justify mirror)
			)
		)
		(property "Value" ""
			(at 0 0 90)
			(layer "B.Fab")
			(effects
				(font
					(size 1.27 1.27)
				)
				(justify mirror)
			)
		)
		(duplicate_pad_numbers_are_jumpers no)
		(fp_line
			(start -0.7874 0.4064)
			(end 0.7874 0.4064)
			(stroke
				(width 0.1524)
				(type default)
			)
			(layer "B.SilkS")
		)
		(fp_line
			(start 0.7874 0.4064)
			(end 0.7874 -0.4064)
			(stroke
				(width 0.1524)
				(type default)
			)
			(layer "B.SilkS")
		)
		(fp_line
			(start -0.7874 -0.4064)
			(end -0.7874 0.4064)
			(stroke
				(width 0.1524)
				(type default)
			)
			(layer "B.SilkS")
		)
		(fp_line
			(start 0.7874 -0.4064)
			(end -0.7874 -0.4064)
			(stroke
				(width 0.1524)
				(type default)
			)
			(layer "B.SilkS")
		)
		(fp_line
			(start -0.67945 0.3048)
			(end -0.120396 0.3048)
			(stroke
				(width 0.1)
				(type default)
			)
			(layer "B.Fab")
		)
		(fp_line
			(start -0.120396 0.3048)
			(end -0.120396 0.2794)
			(stroke
				(width 0.1)
				(type default)
			)
			(layer "B.Fab")
		)
		(fp_line
			(start 0.12065 0.3048)
			(end 0.67945 0.3048)
			(stroke
				(width 0.1)
				(type default)
			)
			(layer "B.Fab")
		)
		(fp_line
			(start 0.67945 0.3048)
			(end 0.67945 -0.305054)
			(stroke
				(width 0.1)
				(type default)
			)
			(layer "B.Fab")
		)
		(fp_line
			(start -0.120396 0.2794)
			(end 0.12065 0.2794)
			(stroke
				(width 0.1)
				(type default)
			)
			(layer "B.Fab")
		)
		(fp_line
			(start 0.12065 0.2794)
			(end 0.12065 0.3048)
			(stroke
				(width 0.1)
				(type default)
			)
			(layer "B.Fab")
		)
		(fp_line
			(start -0.12065 -0.2794)
			(end -0.12065 -0.3048)
			(stroke
				(width 0.1)
				(type default)
			)
			(layer "B.Fab")
		)
		(fp_line
			(start 0.12065 -0.2794)
			(end -0.12065 -0.2794)
			(stroke
				(width 0.1)
				(type default)
			)
			(layer "B.Fab")
		)
		(fp_line
			(start -0.67945 -0.3048)
			(end -0.67945 0.3048)
			(stroke
				(width 0.1)
				(type default)
			)
			(layer "B.Fab")
		)
		(fp_line
			(start -0.12065 -0.3048)
			(end -0.67945 -0.3048)
			(stroke
				(width 0.1)
				(type default)
			)
			(layer "B.Fab")
		)
		(fp_line
			(start 0.12065 -0.305054)
			(end 0.12065 -0.2794)
			(stroke
				(width 0.1)
				(type default)
			)
			(layer "B.Fab")
		)
		(fp_line
			(start 0.67945 -0.305054)
			(end 0.12065 -0.305054)
			(stroke
				(width 0.1)
				(type default)
			)
			(layer "B.Fab")
		)
		(pad "1" smd circle
			(at 0.40005 0 90)
			(size 0 0)
			(layers "B.Cu" "B.Mask" "B.Paste")
			(net "P3V3_AUX")
		)
		(pad "2" smd circle
			(at -0.40005 0 90)
			(size 0 0)
			(layers "B.Cu" "B.Mask" "B.Paste")
			(net "BMC_EMMC_CD_N")
		)
	)
	(footprint ""
		(layer "B.Cu")
		(at 38.518592 -56.120538)
		(property "Reference" "C42"
			(at 0 0 0)
			(layer "B.SilkS")
			(hide yes)
			(effects
				(font
					(size 1.27 1.27)
				)
				(justify mirror)
			)
		)
		(property "Value" ""
			(at 0 0 0)
			(layer "B.Fab")
			(effects
				(font
					(size 1.27 1.27)
				)
				(justify mirror)
			)
		)
		(duplicate_pad_numbers_are_jumpers no)
		(fp_line
			(start -1.2954 -0.5842)
			(end -1.2954 0.5842)
			(stroke
				(width 0.1524)
				(type default)
			)
			(layer "B.SilkS")
		)
		(fp_line
			(start -1.2954 0.5842)
			(end 1.2954 0.5842)
			(stroke
				(width 0.1524)
				(type default)
			)
			(layer "B.SilkS")
		)
		(fp_line
			(start 0 -0.5842)
			(end 0 0.5842)
			(stroke
				(width 0.1524)
				(type default)
			)
			(layer "B.SilkS")
		)
		(fp_line
			(start 1.2954 -0.5842)
			(end -1.2954 -0.5842)
			(stroke
				(width 0.1524)
				(type default)
			)
			(layer "B.SilkS")
		)
		(fp_line
			(start 1.2954 0.5842)
			(end 1.2954 -0.5842)
			(stroke
				(width 0.1524)
				(type default)
			)
			(layer "B.SilkS")
		)
		(fp_line
			(start -1.1938 -0.4064)
			(end -1.1938 0.4064)
			(stroke
				(width 0.1)
				(type default)
			)
			(layer "B.Fab")
		)
		(fp_line
			(start -1.1938 0.4064)
			(end -0.8636 0.4064)
			(stroke
				(width 0.1)
				(type default)
			)
			(layer "B.Fab")
		)
		(fp_line
			(start -0.8636 -0.4572)
			(end -0.8636 -0.4064)
			(stroke
				(width 0.1)
				(type default)
			)
			(layer "B.Fab")
		)
		(fp_line
			(start -0.8636 -0.4064)
			(end -1.1938 -0.4064)
			(stroke
				(width 0.1)
				(type default)
			)
			(layer "B.Fab")
		)
		(fp_line
			(start -0.8636 0.4064)
			(end -0.8636 0.4572)
			(stroke
				(width 0.1)
				(type default)
			)
			(layer "B.Fab")
		)
		(fp_line
			(start -0.8636 0.4572)
			(end 0.8636 0.4572)
			(stroke
				(width 0.1)
				(type default)
			)
			(layer "B.Fab")
		)
		(fp_line
			(start 0.8636 -0.4572)
			(end -0.8636 -0.4572)
			(stroke
				(width 0.1)
				(type default)
			)
			(layer "B.Fab")
		)
		(fp_line
			(start 0.8636 -0.4064)
			(end 0.8636 -0.4572)
			(stroke
				(width 0.1)
				(type default)
			)
			(layer "B.Fab")
		)
		(fp_line
			(start 0.8636 0.4064)
			(end 1.1938 0.4064)
			(stroke
				(width 0.1)
				(type default)
			)
			(layer "B.Fab")
		)
		(fp_line
			(start 0.8636 0.4572)
			(end 0.8636 0.4064)
			(stroke
				(width 0.1)
				(type default)
			)
			(layer "B.Fab")
		)
		(fp_line
			(start 1.1938 -0.4064)
			(end 0.8636 -0.4064)
			(stroke
				(width 0.1)
				(type default)
			)
			(layer "B.Fab")
		)
		(fp_line
			(start 1.1938 0.4064)
			(end 1.1938 -0.4064)
			(stroke
				(width 0.1)
				(type default)
			)
			(layer "B.Fab")
		)
		(pad "1" smd rect
			(at 0.7366 0 270)
			(size 0.7112 0.8128)
			(layers "B.Cu" "B.Mask" "B.Paste")
			(net "PVCCIO_PECI_BMC")
		)
		(pad "2" smd rect
			(at -0.7366 0 270)
			(size 0.7112 0.8128)
			(layers "B.Cu" "B.Mask" "B.Paste")
			(net "GND")
		)
	)
	(footprint ""
		(layer "B.Cu")
		(at 76.162154 -52.286916 180)
		(property "Reference" "C4"
			(at 0 0 0)
			(layer "B.SilkS")
			(hide yes)
			(effects
				(font
					(size 1.27 1.27)
				)
				(justify mirror)
			)
		)
		(property "Value" ""
			(at 0 0 0)
			(layer "B.Fab")
			(effects
				(font
					(size 1.27 1.27)
				)
				(justify mirror)
			)
		)
		(duplicate_pad_numbers_are_jumpers no)
		(fp_line
			(start 0.7874 0.4064)
			(end 0.7874 -0.4064)
			(stroke
				(width 0.1524)
				(type default)
			)
			(layer "B.SilkS")
		)
		(fp_line
			(start 0.7874 -0.4064)
			(end -0.7874 -0.4064)
			(stroke
				(width 0.1524)
				(type default)
			)
			(layer "B.SilkS")
		)
		(fp_line
			(start -0.7874 0.4064)
			(end 0.7874 0.4064)
			(stroke
				(width 0.1524)
				(type default)
			)
			(layer "B.SilkS")
		)
		(fp_line
			(start -0.7874 -0.4064)
			(end -0.7874 0.4064)
			(stroke
				(width 0.1524)
				(type default)
			)
			(layer "B.SilkS")
		)
		(fp_line
			(start 0.67945 0.3048)
			(end 0.67945 -0.305054)
			(stroke
				(width 0.1)
				(type default)
			)
			(layer "B.Fab")
		)
		(fp_line
			(start 0.67945 -0.305054)
			(end 0.12065 -0.305054)
			(stroke
				(width 0.1)
				(type default)
			)
			(layer "B.Fab")
		)
		(fp_line
			(start 0.12065 0.3048)
			(end 0.67945 0.3048)
			(stroke
				(width 0.1)
				(type default)
			)
			(layer "B.Fab")
		)
		(fp_line
			(start 0.12065 0.2794)
			(end 0.12065 0.3048)
			(stroke
				(width 0.1)
				(type default)
			)
			(layer "B.Fab")
		)
		(fp_line
			(start 0.12065 -0.2794)
			(end -0.12065 -0.2794)
			(stroke
				(width 0.1)
				(type default)
			)
			(layer "B.Fab")
		)
		(fp_line
			(start 0.12065 -0.305054)
			(end 0.12065 -0.2794)
			(stroke
				(width 0.1)
				(type default)
			)
			(layer "B.Fab")
		)
		(fp_line
			(start -0.120396 0.3048)
			(end -0.120396 0.2794)
			(stroke
				(width 0.1)
				(type default)
			)
			(layer "B.Fab")
		)
		(fp_line
			(start -0.120396 0.2794)
			(end 0.12065 0.2794)
			(stroke
				(width 0.1)
				(type default)
			)
			(layer "B.Fab")
		)
		(fp_line
			(start -0.12065 -0.2794)
			(end -0.12065 -0.3048)
			(stroke
				(width 0.1)
				(type default)
			)
			(layer "B.Fab")
		)
		(fp_line
			(start -0.12065 -0.3048)
			(end -0.67945 -0.3048)
			(stroke
				(width 0.1)
				(type default)
			)
			(layer "B.Fab")
		)
		(fp_line
			(start -0.67945 0.3048)
			(end -0.120396 0.3048)
			(stroke
				(width 0.1)
				(type default)
			)
			(layer "B.Fab")
		)
		(fp_line
			(start -0.67945 -0.3048)
			(end -0.67945 0.3048)
			(stroke
				(width 0.1)
				(type default)
			)
			(layer "B.Fab")
		)
		(pad "1" smd circle
			(at 0.40005 0)
			(size 0 0)
			(layers "B.Cu" "B.Mask" "B.Paste")
			(net "P1V2_AUX")
		)
		(pad "2" smd circle
			(at -0.40005 0)
			(size 0 0)
			(layers "B.Cu" "B.Mask" "B.Paste")
			(net "GND")
		)
	)
	(footprint ""
		(layer "B.Cu")
		(at 71.66102 -44.61129)
		(property "Reference" "C10"
			(at 0 0 0)
			(layer "B.SilkS")
			(hide yes)
			(effects
				(font
					(size 1.27 1.27)
				)
				(justify mirror)
			)
		)
		(property "Value" ""
			(at 0 0 0)
			(layer "B.Fab")
			(effects
				(font
					(size 1.27 1.27)
				)
				(justify mirror)
			)
		)
		(duplicate_pad_numbers_are_jumpers no)
		(fp_line
			(start -0.7874 -0.4064)
			(end -0.7874 0.4064)
			(stroke
				(width 0.1524)
				(type default)
			)
			(layer "B.SilkS")
		)
		(fp_line
			(start -0.7874 0.4064)
			(end 0.7874 0.4064)
			(stroke
				(width 0.1524)
				(type default)
			)
			(layer "B.SilkS")
		)
		(fp_line
			(start 0.7874 -0.4064)
			(end -0.7874 -0.4064)
			(stroke
				(width 0.1524)
				(type default)
			)
			(layer "B.SilkS")
		)
		(fp_line
			(start 0.7874 0.4064)
			(end 0.7874 -0.4064)
			(stroke
				(width 0.1524)
				(type default)
			)
			(layer "B.SilkS")
		)
		(fp_line
			(start -0.67945 -0.3048)
			(end -0.67945 0.3048)
			(stroke
				(width 0.1)
				(type default)
			)
			(layer "B.Fab")
		)
		(fp_line
			(start -0.67945 0.3048)
			(end -0.120396 0.3048)
			(stroke
				(width 0.1)
				(type default)
			)
			(layer "B.Fab")
		)
		(fp_line
			(start -0.12065 -0.3048)
			(end -0.67945 -0.3048)
			(stroke
				(width 0.1)
				(type default)
			)
			(layer "B.Fab")
		)
		(fp_line
			(start -0.12065 -0.2794)
			(end -0.12065 -0.3048)
			(stroke
				(width 0.1)
				(type default)
			)
			(layer "B.Fab")
		)
		(fp_line
			(start -0.120396 0.2794)
			(end 0.12065 0.2794)
			(stroke
				(width 0.1)
				(type default)
			)
			(layer "B.Fab")
		)
		(fp_line
			(start -0.120396 0.3048)
			(end -0.120396 0.2794)
			(stroke
				(width 0.1)
				(type default)
			)
			(layer "B.Fab")
		)
		(fp_line
			(start 0.12065 -0.305054)
			(end 0.12065 -0.2794)
			(stroke
				(width 0.1)
				(type default)
			)
			(layer "B.Fab")
		)
		(fp_line
			(start 0.12065 -0.2794)
			(end -0.12065 -0.2794)
			(stroke
				(width 0.1)
				(type default)
			)
			(layer "B.Fab")
		)
		(fp_line
			(start 0.12065 0.2794)
			(end 0.12065 0.3048)
			(stroke
				(width 0.1)
				(type default)
			)
			(layer "B.Fab")
		)
		(fp_line
			(start 0.12065 0.3048)
			(end 0.67945 0.3048)
			(stroke
				(width 0.1)
				(type default)
			)
			(layer "B.Fab")
		)
		(fp_line
			(start 0.67945 -0.305054)
			(end 0.12065 -0.305054)
			(stroke
				(width 0.1)
				(type default)
			)
			(layer "B.Fab")
		)
		(fp_line
			(start 0.67945 0.3048)
			(end 0.67945 -0.305054)
			(stroke
				(width 0.1)
				(type default)
			)
			(layer "B.Fab")
		)
		(pad "1" smd circle
			(at 0.40005 0 180)
			(size 0 0)
			(layers "B.Cu" "B.Mask" "B.Paste")
			(net "P0V6_DDR_VREF_AUX")
		)
		(pad "2" smd circle
			(at -0.40005 0 180)
			(size 0 0)
			(layers "B.Cu" "B.Mask" "B.Paste")
			(net "GND")
		)
	)
	(footprint ""
		(layer "B.Cu")
		(at 50.91684 -63.94704 90)
		(property "Reference" "R844"
			(at 0 0 90)
			(layer "B.SilkS")
			(hide yes)
			(effects
				(font
					(size 1.27 1.27)
				)
				(justify mirror)
			)
		)
		(property "Value" ""
			(at 0 0 90)
			(layer "B.Fab")
			(effects
				(font
					(size 1.27 1.27)
				)
				(justify mirror)
			)
		)
		(duplicate_pad_numbers_are_jumpers no)
		(fp_line
			(start 0.7874 -0.4064)
			(end -0.7874 -0.4064)
			(stroke
				(width 0.1524)
				(type default)
			)
			(layer "B.SilkS")
		)
		(fp_line
			(start -0.7874 -0.4064)
			(end -0.7874 0.4064)
			(stroke
				(width 0.1524)
				(type default)
			)
			(layer "B.SilkS")
		)
		(fp_line
			(start 0.7874 0.4064)
			(end 0.7874 -0.4064)
			(stroke
				(width 0.1524)
				(type default)
			)
			(layer "B.SilkS")
		)
		(fp_line
			(start -0.7874 0.4064)
			(end 0.7874 0.4064)
			(stroke
				(width 0.1524)
				(type default)
			)
			(layer "B.SilkS")
		)
		(fp_line
			(start 0.67945 -0.305054)
			(end 0.12065 -0.305054)
			(stroke
				(width 0.1)
				(type default)
			)
			(layer "B.Fab")
		)
		(fp_line
			(start 0.12065 -0.305054)
			(end 0.12065 -0.2794)
			(stroke
				(width 0.1)
				(type default)
			)
			(layer "B.Fab")
		)
		(fp_line
			(start -0.12065 -0.3048)
			(end -0.67945 -0.3048)
			(stroke
				(width 0.1)
				(type default)
			)
			(layer "B.Fab")
		)
		(fp_line
			(start -0.67945 -0.3048)
			(end -0.67945 0.3048)
			(stroke
				(width 0.1)
				(type default)
			)
			(layer "B.Fab")
		)
		(fp_line
			(start 0.12065 -0.2794)
			(end -0.12065 -0.2794)
			(stroke
				(width 0.1)
				(type default)
			)
			(layer "B.Fab")
		)
		(fp_line
			(start -0.12065 -0.2794)
			(end -0.12065 -0.3048)
			(stroke
				(width 0.1)
				(type default)
			)
			(layer "B.Fab")
		)
		(fp_line
			(start 0.12065 0.2794)
			(end 0.12065 0.3048)
			(stroke
				(width 0.1)
				(type default)
			)
			(layer "B.Fab")
		)
		(fp_line
			(start -0.120396 0.2794)
			(end 0.12065 0.2794)
			(stroke
				(width 0.1)
				(type default)
			)
			(layer "B.Fab")
		)
		(fp_line
			(start 0.67945 0.3048)
			(end 0.67945 -0.305054)
			(stroke
				(width 0.1)
				(type default)
			)
			(layer "B.Fab")
		)
		(fp_line
			(start 0.12065 0.3048)
			(end 0.67945 0.3048)
			(stroke
				(width 0.1)
				(type default)
			)
			(layer "B.Fab")
		)
		(fp_line
			(start -0.120396 0.3048)
			(end -0.120396 0.2794)
			(stroke
				(width 0.1)
				(type default)
			)
			(layer "B.Fab")
		)
		(fp_line
			(start -0.67945 0.3048)
			(end -0.120396 0.3048)
			(stroke
				(width 0.1)
				(type default)
			)
			(layer "B.Fab")
		)
		(pad "1" smd circle
			(at 0.40005 0 270)
			(size 0 0)
			(layers "B.Cu" "B.Mask" "B.Paste")
			(net "P3V3_AUX")
		)
		(pad "2" smd circle
			(at -0.40005 0 270)
			(size 0 0)
			(layers "B.Cu" "B.Mask" "B.Paste")
			(net "SMB_BMC_ALERT12_N")
		)
	)
	(footprint ""
		(layer "B.Cu")
		(at 57.906666 -73.645014)
		(property "Reference" "C295"
			(at 0 0 0)
			(layer "B.SilkS")
			(hide yes)
			(effects
				(font
					(size 1.27 1.27)
				)
				(justify mirror)
			)
		)
		(property "Value" ""
			(at 0 0 0)
			(layer "B.Fab")
			(effects
				(font
					(size 1.27 1.27)
				)
				(justify mirror)
			)
		)
		(duplicate_pad_numbers_are_jumpers no)
		(fp_line
			(start -0.7874 -0.4064)
			(end -0.7874 0.4064)
			(stroke
				(width 0.1524)
				(type default)
			)
			(layer "B.SilkS")
		)
		(fp_line
			(start -0.7874 0.4064)
			(end 0.7874 0.4064)
			(stroke
				(width 0.1524)
				(type default)
			)
			(layer "B.SilkS")
		)
		(fp_line
			(start 0.7874 -0.4064)
			(end -0.7874 -0.4064)
			(stroke
				(width 0.1524)
				(type default)
			)
			(layer "B.SilkS")
		)
		(fp_line
			(start 0.7874 0.4064)
			(end 0.7874 -0.4064)
			(stroke
				(width 0.1524)
				(type default)
			)
			(layer "B.SilkS")
		)
		(fp_line
			(start -0.67945 -0.3048)
			(end -0.67945 0.3048)
			(stroke
				(width 0.1)
				(type default)
			)
			(layer "B.Fab")
		)
		(fp_line
			(start -0.67945 0.3048)
			(end -0.120396 0.3048)
			(stroke
				(width 0.1)
				(type default)
			)
			(layer "B.Fab")
		)
		(fp_line
			(start -0.12065 -0.3048)
			(end -0.67945 -0.3048)
			(stroke
				(width 0.1)
				(type default)
			)
			(layer "B.Fab")
		)
		(fp_line
			(start -0.12065 -0.2794)
			(end -0.12065 -0.3048)
			(stroke
				(width 0.1)
				(type default)
			)
			(layer "B.Fab")
		)
		(fp_line
			(start -0.120396 0.2794)
			(end 0.12065 0.2794)
			(stroke
				(width 0.1)
				(type default)
			)
			(layer "B.Fab")
		)
		(fp_line
			(start -0.120396 0.3048)
			(end -0.120396 0.2794)
			(stroke
				(width 0.1)
				(type default)
			)
			(layer "B.Fab")
		)
		(fp_line
			(start 0.12065 -0.305054)
			(end 0.12065 -0.2794)
			(stroke
				(width 0.1)
				(type default)
			)
			(layer "B.Fab")
		)
		(fp_line
			(start 0.12065 -0.2794)
			(end -0.12065 -0.2794)
			(stroke
				(width 0.1)
				(type default)
			)
			(layer "B.Fab")
		)
		(fp_line
			(start 0.12065 0.2794)
			(end 0.12065 0.3048)
			(stroke
				(width 0.1)
				(type default)
			)
			(layer "B.Fab")
		)
		(fp_line
			(start 0.12065 0.3048)
			(end 0.67945 0.3048)
			(stroke
				(width 0.1)
				(type default)
			)
			(layer "B.Fab")
		)
		(fp_line
			(start 0.67945 -0.305054)
			(end 0.12065 -0.305054)
			(stroke
				(width 0.1)
				(type default)
			)
			(layer "B.Fab")
		)
		(fp_line
			(start 0.67945 0.3048)
			(end 0.67945 -0.305054)
			(stroke
				(width 0.1)
				(type default)
			)
			(layer "B.Fab")
		)
		(pad "1" smd circle
			(at 0.40005 0 180)
			(size 0 0)
			(layers "B.Cu" "B.Mask" "B.Paste")
			(net "P5V_SENSOR")
		)
		(pad "2" smd circle
			(at -0.40005 0 180)
			(size 0 0)
			(layers "B.Cu" "B.Mask" "B.Paste")
			(net "GND")
		)
	)
)
